(kicad_pcb
	(version 20241229)
	(generator "pcbnew")
	(generator_version "9.0")
	(general
		(thickness 1.59)
		(legacy_teardrops no)
	)
	(paper "A3")
	(title_block
		(title "usb-c-power-adapter")
		(date "2025-06-24")
		(rev "1.1.2")
		(company "Antmicro")
		(comment 9 "footprints 22-26 of 122")
	)
	(layers
		(0 "F.Cu" signal)
		(4 "In1.Cu" signal)
		(6 "In2.Cu" signal)
		(2 "B.Cu" signal)
		(9 "F.Adhes" user "F.Adhesive")
		(11 "B.Adhes" user "B.Adhesive")
		(13 "F.Paste" user)
		(15 "B.Paste" user)
		(5 "F.SilkS" user "F.Silkscreen")
		(7 "B.SilkS" user "B.Silkscreen")
		(1 "F.Mask" user)
		(3 "B.Mask" user)
		(17 "Dwgs.User" user "User.Drawings")
		(19 "Cmts.User" user "User.Comments")
		(21 "Eco1.User" user "User.Eco1")
		(23 "Eco2.User" user "User.Eco2")
		(25 "Edge.Cuts" user)
		(27 "Margin" user)
		(31 "F.CrtYd" user "F.Courtyard")
		(29 "B.CrtYd" user "B.Courtyard")
		(35 "F.Fab" user)
		(33 "B.Fab" user)
	)
	(footprint "antmicro-footprints:C_0805_2012Metric"
		(layer "F.Cu")
		(at 95.401 72.25 180)
		(descr "Capacitor SMD 0805")
		(tags "capacitor SMD 0805")
		(property "Reference" "C7"
			(at -1.5 -11.5 0)
			(layer "B.SilkS")
			(effects
				(font
					(size 0.7 0.7)
					(thickness 0.15)
				)
				(justify right bottom mirror)
			)
		)
		(property "Value" "C_10u_0805_35V"
			(at -2.055717 1.963152 0)
			(layer "F.Fab")
			(effects
				(font
					(size 0.7 0.7)
					(thickness 0.15)
				)
				(justify right bottom)
			)
		)
		(property "Datasheet" "https://www.murata.com/products/productdetail?partno=GRM21BR6YA106KE43%23"
			(at 0 0 180)
			(layer "F.Fab")
			(hide yes)
			(effects
				(font
					(size 1.27 1.27)
					(thickness 0.15)
				)
			)
		)
		(property "Description" "SMD Multilayer Ceramic Capacitor, 10 µF, 35 V, 0805 [2012 Metric], ± 10%, X5R, GRM Series"
			(at 0 0 180)
			(layer "F.Fab")
			(hide yes)
			(effects
				(font
					(size 1.27 1.27)
					(thickness 0.15)
				)
			)
		)
		(property "MPN" "GRM21BR6YA106KE43L"
			(at 0 0 180)
			(unlocked yes)
			(layer "F.Fab")
			(hide yes)
			(effects
				(font
					(size 1 1)
					(thickness 0.15)
				)
			)
		)
		(property "Manufacturer" "Murata"
			(at 0 0 180)
			(unlocked yes)
			(layer "F.Fab")
			(hide yes)
			(effects
				(font
					(size 1 1)
					(thickness 0.15)
				)
			)
		)
		(property "License" "Apache-2.0"
			(at 0 0 180)
			(unlocked yes)
			(layer "F.Fab")
			(hide yes)
			(effects
				(font
					(size 1 1)
					(thickness 0.15)
				)
			)
		)
		(property "Author" "Antmicro"
			(at 0 0 180)
			(unlocked yes)
			(layer "F.Fab")
			(hide yes)
			(effects
				(font
					(size 1 1)
					(thickness 0.15)
				)
			)
		)
		(property "Val" "10u"
			(at 0 0 180)
			(unlocked yes)
			(layer "F.Fab")
			(hide yes)
			(effects
				(font
					(size 1 1)
					(thickness 0.15)
				)
			)
		)
		(property "Voltage" "35V"
			(at 0 0 180)
			(unlocked yes)
			(layer "F.Fab")
			(hide yes)
			(effects
				(font
					(size 1 1)
					(thickness 0.15)
				)
			)
		)
		(property "Dielectric" ""
			(at 0 0 180)
			(unlocked yes)
			(layer "F.Fab")
			(hide yes)
			(effects
				(font
					(size 1 1)
					(thickness 0.15)
				)
			)
		)
		(property "Public" "False"
			(at 0 0 180)
			(unlocked yes)
			(layer "F.Fab")
			(hide yes)
			(effects
				(font
					(size 1 1)
					(thickness 0.15)
				)
			)
		)
		(sheetname "/USB PD/")
		(sheetfile "usb_pd.kicad_sch")
		(attr smd)
		(fp_line
			(start -0.3 0.7)
			(end 0.3 0.7)
			(stroke
				(width 0.15)
				(type solid)
			)
			(layer "F.SilkS")
		)
		(fp_line
			(start -0.3 -0.7)
			(end 0.3 -0.7)
			(stroke
				(width 0.15)
				(type solid)
			)
			(layer "F.SilkS")
		)
		(fp_rect
			(start 1.95 -0.9)
			(end -1.95 0.9)
			(stroke
				(width 0.05)
				(type default)
			)
			(fill no)
			(layer "F.CrtYd")
		)
		(fp_rect
			(start -0.95 -0.675)
			(end 0.95 0.675)
			(stroke
				(width 0.15)
				(type solid)
			)
			(fill no)
			(layer "F.Fab")
		)
		(pad "1" smd roundrect
			(at -1.1 0 180)
			(size 1.2 1.3)
			(layers "F.Cu" "F.Mask" "F.Paste")
			(roundrect_rratio 0.25)
			(net 2 "GND")
			(pintype "passive")
		)
		(pad "2" smd roundrect
			(at 1.1 0 180)
			(size 1.2 1.3)
			(layers "F.Cu" "F.Mask" "F.Paste")
			(roundrect_rratio 0.25)
			(net 63 "Net-(D1-C)")
			(pintype "passive")
		)
	)
	(footprint "antmicro-footprints:C_0402_1005Metric"
		(layer "F.Cu")
		(at 89.4 71.7 180)
		(descr "Capacitor SMD 0402")
		(tags "capacitor SMD 0402")
		(property "Reference" "C11"
			(at -4.41 0.35 90)
			(layer "B.SilkS")
			(effects
				(font
					(size 0.7 0.7)
					(thickness 0.15)
				)
				(justify left bottom mirror)
			)
		)
		(property "Value" "C_1u_25V_0402"
			(at -1.022927 2.155213 0)
			(layer "F.Fab")
			(effects
				(font
					(size 0.7 0.7)
					(thickness 0.15)
				)
				(justify right bottom)
			)
		)
		(property "Datasheet" "https://www.murata.com/products/productdetail?partno=GRM155R61E105KE11%23"
			(at 0 0 180)
			(layer "F.Fab")
			(hide yes)
			(effects
				(font
					(size 1.27 1.27)
					(thickness 0.15)
				)
			)
		)
		(property "Description" "SMD Multilayer Ceramic Capacitor, 1 µF, 25 V, 0402 [1005 Metric], ± 10%, X5R, GRM Series"
			(at 0 0 180)
			(layer "F.Fab")
			(hide yes)
			(effects
				(font
					(size 1.27 1.27)
					(thickness 0.15)
				)
			)
		)
		(property "MPN" "GRM155R61E105KE11J"
			(at 0 0 180)
			(unlocked yes)
			(layer "F.Fab")
			(hide yes)
			(effects
				(font
					(size 1 1)
					(thickness 0.15)
				)
			)
		)
		(property "Manufacturer" "Murata"
			(at 0 0 180)
			(unlocked yes)
			(layer "F.Fab")
			(hide yes)
			(effects
				(font
					(size 1 1)
					(thickness 0.15)
				)
			)
		)
		(property "License" "Apache-2.0"
			(at 0 0 180)
			(unlocked yes)
			(layer "F.Fab")
			(hide yes)
			(effects
				(font
					(size 1 1)
					(thickness 0.15)
				)
			)
		)
		(property "Author" "Antmicro"
			(at 0 0 180)
			(unlocked yes)
			(layer "F.Fab")
			(hide yes)
			(effects
				(font
					(size 1 1)
					(thickness 0.15)
				)
			)
		)
		(property "Val" "1u"
			(at 0 0 180)
			(unlocked yes)
			(layer "F.Fab")
			(hide yes)
			(effects
				(font
					(size 1 1)
					(thickness 0.15)
				)
			)
		)
		(property "Voltage" "25V"
			(at 0 0 180)
			(unlocked yes)
			(layer "F.Fab")
			(hide yes)
			(effects
				(font
					(size 1 1)
					(thickness 0.15)
				)
			)
		)
		(property "Dielectric" "X5R"
			(at 0 0 180)
			(unlocked yes)
			(layer "F.Fab")
			(hide yes)
			(effects
				(font
					(size 1 1)
					(thickness 0.15)
				)
			)
		)
		(sheetname "/USB PD/")
		(sheetfile "usb_pd.kicad_sch")
		(attr smd)
		(fp_rect
			(start -0.925 -0.47)
			(end 0.925 0.47)
			(stroke
				(width 0.05)
				(type default)
			)
			(fill no)
			(layer "F.CrtYd")
		)
		(fp_line
			(start 0.504 0.248)
			(end -0.494 0.248)
			(stroke
				(width 0.15)
				(type solid)
			)
			(layer "F.Fab")
		)
		(fp_line
			(start 0.504 -0.25)
			(end 0.504 0.248)
			(stroke
				(width 0.15)
				(type solid)
			)
			(layer "F.Fab")
		)
		(fp_line
			(start -0.494 0.248)
			(end -0.494 -0.25)
			(stroke
				(width 0.15)
				(type solid)
			)
			(layer "F.Fab")
		)
		(fp_line
			(start -0.494 -0.25)
			(end 0.504 -0.25)
			(stroke
				(width 0.15)
				(type solid)
			)
			(layer "F.Fab")
		)
		(pad "1" smd roundrect
			(at -0.48 0 180)
			(size 0.59 0.64)
			(layers "F.Cu" "F.Mask" "F.Paste")
			(roundrect_rratio 0.25)
			(net 2 "GND")
			(pintype "passive")
		)
		(pad "2" smd roundrect
			(at 0.48 0 180)
			(size 0.59 0.64)
			(layers "F.Cu" "F.Mask" "F.Paste")
			(roundrect_rratio 0.25)
			(net 6 "VBUS")
			(pintype "passive")
		)
	)
	(footprint "antmicro-footprints:L_Abracon_ASPIAIG-Q8080"
		(layer "F.Cu")
		(at 98.3 95.425 -90)
		(property "Reference" "L1"
			(at -5.025 5.9 0)
			(unlocked yes)
			(layer "F.SilkS")
			(effects
				(font
					(size 0.7 0.7)
					(thickness 0.15)
				)
				(justify left bottom)
			)
		)
		(property "Value" "L_4u7_14.6A_Abracon-Q8080"
			(at 0 10.16 270)
			(unlocked yes)
			(layer "F.Fab")
			(effects
				(font
					(size 0.7 0.7)
					(thickness 0.15)
				)
				(justify left bottom)
			)
		)
		(property "Datasheet" "https://www.mouser.com/datasheet/2/3/ASPIAIG_Q8080-2256550.pdf"
			(at 0 0 270)
			(layer "F.Fab")
			(hide yes)
			(effects
				(font
					(size 1.27 1.27)
					(thickness 0.15)
				)
			)
		)
		(property "Description" "Power Inductors - SMD 4.7 UH 20%"
			(at 0 0 270)
			(layer "F.Fab")
			(hide yes)
			(effects
				(font
					(size 1.27 1.27)
					(thickness 0.15)
				)
			)
		)
		(property "MPN" "ASPIAIG-Q8080-4R7M-T"
			(at 0 0 270)
			(unlocked yes)
			(layer "F.Fab")
			(hide yes)
			(effects
				(font
					(size 1 1)
					(thickness 0.15)
				)
			)
		)
		(property "ISat" "17A"
			(at 0 0 270)
			(unlocked yes)
			(layer "F.Fab")
			(hide yes)
			(effects
				(font
					(size 1 1)
					(thickness 0.15)
				)
			)
		)
		(property "IMax" "14.6A"
			(at 0 0 270)
			(unlocked yes)
			(layer "F.Fab")
			(hide yes)
			(effects
				(font
					(size 1 1)
					(thickness 0.15)
				)
			)
		)
		(property "Size" "8.9x8.5"
			(at 0 0 270)
			(unlocked yes)
			(layer "F.Fab")
			(hide yes)
			(effects
				(font
					(size 1 1)
					(thickness 0.15)
				)
			)
		)
		(property "Val" "4.7u/14.6A"
			(at 0 0 270)
			(unlocked yes)
			(layer "F.Fab")
			(hide yes)
			(effects
				(font
					(size 1 1)
					(thickness 0.15)
				)
			)
		)
		(property "Author" "Antmicro"
			(at 0 0 270)
			(unlocked yes)
			(layer "F.Fab")
			(hide yes)
			(effects
				(font
					(size 1 1)
					(thickness 0.15)
				)
			)
		)
		(property "License" "Apache-2.0"
			(at 0 0 270)
			(unlocked yes)
			(layer "F.Fab")
			(hide yes)
			(effects
				(font
					(size 1 1)
					(thickness 0.15)
				)
			)
		)
		(property "Manufacturer" "Abracon"
			(at 0 0 270)
			(unlocked yes)
			(layer "F.Fab")
			(hide yes)
			(effects
				(font
					(size 1 1)
					(thickness 0.15)
				)
			)
		)
		(sheetname "/DC-DC Converters/")
		(sheetfile "dc-dc_converters.kicad_sch")
		(attr smd)
		(fp_rect
			(start -4.6 -4.4)
			(end 4.6 4.4)
			(stroke
				(width 0.15)
				(type default)
			)
			(fill no)
			(layer "F.SilkS")
		)
		(fp_rect
			(start -4.85 -4.64)
			(end 4.85 4.64)
			(stroke
				(width 0.05)
				(type solid)
			)
			(fill no)
			(layer "F.CrtYd")
		)
		(fp_rect
			(start -4.597 -4.394)
			(end 4.597 4.394)
			(stroke
				(width 0.15)
				(type default)
			)
			(fill no)
			(layer "F.Fab")
		)
		(pad "1" smd roundrect
			(at -2.675 0 270)
			(size 2.65 7.8)
			(layers "F.Cu" "F.Mask" "F.Paste")
			(roundrect_rratio 0.05)
			(net 8 "Net-(L1-Pad1)")
			(pintype "passive")
		)
		(pad "2" smd roundrect
			(at 2.675 0 270)
			(size 2.65 7.8)
			(layers "F.Cu" "F.Mask" "F.Paste")
			(roundrect_rratio 0.05)
			(net 5 "+12V")
			(pintype "passive")
		)
	)
	(footprint "antmicro-footprints:Vishay_PowerPAK_1212-8_Single"
		(layer "F.Cu")
		(at 88.8 78.65 -90)
		(descr "PowerPAK 1212-8 Single")
		(tags "Vishay PowerPAK 1212-8 Single")
		(property "Reference" "Q1"
			(at 0.19 -5.236 180)
			(layer "F.SilkS")
			(effects
				(font
					(size 0.7 0.7)
					(thickness 0.15)
				)
				(justify right bottom)
			)
		)
		(property "Value" "SQS401EN-T1_BE3"
			(at 0 2.7 90)
			(layer "F.Fab")
			(effects
				(font
					(size 0.7 0.7)
					(thickness 0.15)
				)
				(justify right bottom)
			)
		)
		(property "Datasheet" "https://www.vishay.com/docs/65529/sqs401en.pdf"
			(at 0 0 270)
			(layer "F.Fab")
			(hide yes)
			(effects
				(font
					(size 1.27 1.27)
					(thickness 0.15)
				)
			)
		)
		(property "Description" "MOSFET, P Channel, 40 V, 16A, 0.047 ohm, PowerPAK 1212-8, Surface Mount"
			(at 0 0 270)
			(layer "F.Fab")
			(hide yes)
			(effects
				(font
					(size 1.27 1.27)
					(thickness 0.15)
				)
			)
		)
		(property "MPN" "SQS401EN-T1_BE3"
			(at 0 0 270)
			(unlocked yes)
			(layer "F.Fab")
			(hide yes)
			(effects
				(font
					(size 1 1)
					(thickness 0.15)
				)
			)
		)
		(property "Manufacturer" "Vishay"
			(at 0 0 270)
			(unlocked yes)
			(layer "F.Fab")
			(hide yes)
			(effects
				(font
					(size 1 1)
					(thickness 0.15)
				)
			)
		)
		(property "Author" "Antmicro"
			(at 0 0 270)
			(unlocked yes)
			(layer "F.Fab")
			(hide yes)
			(effects
				(font
					(size 1 1)
					(thickness 0.15)
				)
			)
		)
		(property "License" "Apache-2.0"
			(at 0 0 270)
			(unlocked yes)
			(layer "F.Fab")
			(hide yes)
			(effects
				(font
					(size 1 1)
					(thickness 0.15)
				)
			)
		)
		(sheetname "/USB PD/")
		(sheetfile "usb_pd.kicad_sch")
		(attr smd)
		(fp_line
			(start -1.635 1.634)
			(end 1.634 1.634)
			(stroke
				(width 0.15)
				(type solid)
			)
			(layer "F.SilkS")
		)
		(fp_line
			(start -1.635 1.3)
			(end -1.635 1.634)
			(stroke
				(width 0.15)
				(type solid)
			)
			(layer "F.SilkS")
		)
		(fp_line
			(start 1.634 1.3)
			(end 1.634 1.634)
			(stroke
				(width 0.15)
				(type solid)
			)
			(layer "F.SilkS")
		)
		(fp_line
			(start -1.651 -1.651)
			(end -1.651 -1.317)
			(stroke
				(width 0.15)
				(type solid)
			)
			(layer "F.SilkS")
		)
		(fp_line
			(start -1.651 -1.651)
			(end 1.648 -1.651)
			(stroke
				(width 0.15)
				(type solid)
			)
			(layer "F.SilkS")
		)
		(fp_line
			(start 1.648 -1.651)
			(end 1.648 -1.317)
			(stroke
				(width 0.15)
				(type solid)
			)
			(layer "F.SilkS")
		)
		(fp_circle
			(center -1.9 -1.4)
			(end -1.85 -1.4)
			(stroke
				(width 0.15)
				(type solid)
			)
			(fill yes)
			(layer "F.SilkS")
		)
		(fp_rect
			(start -2 -1.8)
			(end 2 1.798)
			(stroke
				(width 0.05)
				(type solid)
			)
			(fill no)
			(layer "F.CrtYd")
		)
		(fp_line
			(start -1.6425 -1.4175)
			(end -1.4175 -1.6425)
			(stroke
				(width 0.15)
				(type solid)
			)
			(layer "F.Fab")
		)
		(fp_rect
			(start -1.651 -1.651)
			(end 1.648 1.648)
			(stroke
				(width 0.15)
				(type solid)
			)
			(fill no)
			(layer "F.Fab")
		)
		(pad "1" smd rect
			(at -1.436 -0.99 270)
			(size 0.99 0.405)
			(layers "F.Cu" "F.Mask" "F.Paste")
			(net 6 "VBUS")
			(pinfunction "S")
			(pintype "passive")
		)
		(pad "2" smd rect
			(at -1.436 -0.332 270)
			(size 0.99 0.405)
			(layers "F.Cu" "F.Mask" "F.Paste")
			(net 6 "VBUS")
			(pinfunction "S")
			(pintype "passive")
		)
		(pad "3" smd rect
			(at -1.436 0.33 270)
			(size 0.99 0.405)
			(layers "F.Cu" "F.Mask" "F.Paste")
			(net 6 "VBUS")
			(pinfunction "S")
			(pintype "passive")
		)
		(pad "4" smd rect
			(at -1.436 0.988 270)
			(size 0.99 0.405)
			(layers "F.Cu" "F.Mask" "F.Paste")
			(net 7 "Net-(Q1-G)")
			(pinfunction "G")
			(pintype "input")
		)
		(pad "5" smd custom
			(at 0.557 0 270)
			(size 1.725 2.235)
			(layers "F.Cu" "F.Mask" "F.Paste")
			(net 3 "VCC")
			(pinfunction "D")
			(pintype "passive")
			(zone_connect 2)
			(options
				(clearance outline)
				(anchor rect)
			)
			(primitives
				(gr_poly
					(pts
						(xy 0.8625 0.1275) (xy 0.8625 -0.1275) (xy 1.3725 -0.1275) (xy 1.3725 -0.5325) (xy 0.8625 -0.5325)
						(xy 0.8625 -0.7875) (xy 1.3725 -0.7875) (xy 1.3725 -1.195) (xy 0.6125 -1.195) (xy 0.6125 1.195)
						(xy 1.3725 1.195) (xy 1.3725 0.7875) (xy 0.8625 0.7875) (xy 0.8625 0.5325) (xy 1.3725 0.5325)
						(xy 1.3725 0.1275)
					)
					(width 0)
					(fill yes)
				)
			)
		)
	)
	(footprint "antmicro-footprints:C_0402_1005Metric"
		(layer "F.Cu")
		(at 89.4 72.7 180)
		(descr "Capacitor SMD 0402")
		(tags "capacitor SMD 0402")
		(property "Reference" "C8"
			(at -5.426 1.35 90)
			(layer "B.SilkS")
			(effects
				(font
					(size 0.7 0.7)
					(thickness 0.15)
				)
				(justify left bottom mirror)
			)
		)
		(property "Value" "C_1u_25V_0402"
			(at -1.022927 2.155213 0)
			(layer "F.Fab")
			(effects
				(font
					(size 0.7 0.7)
					(thickness 0.15)
				)
				(justify right bottom)
			)
		)
		(property "Datasheet" "https://www.murata.com/products/productdetail?partno=GRM155R61E105KE11%23"
			(at 0 0 180)
			(layer "F.Fab")
			(hide yes)
			(effects
				(font
					(size 1.27 1.27)
					(thickness 0.15)
				)
			)
		)
		(property "Description" "SMD Multilayer Ceramic Capacitor, 1 µF, 25 V, 0402 [1005 Metric], ± 10%, X5R, GRM Series"
			(at 0 0 180)
			(layer "F.Fab")
			(hide yes)
			(effects
				(font
					(size 1.27 1.27)
					(thickness 0.15)
				)
			)
		)
		(property "MPN" "GRM155R61E105KE11J"
			(at 0 0 180)
			(unlocked yes)
			(layer "F.Fab")
			(hide yes)
			(effects
				(font
					(size 1 1)
					(thickness 0.15)
				)
			)
		)
		(property "Manufacturer" "Murata"
			(at 0 0 180)
			(unlocked yes)
			(layer "F.Fab")
			(hide yes)
			(effects
				(font
					(size 1 1)
					(thickness 0.15)
				)
			)
		)
		(property "License" "Apache-2.0"
			(at 0 0 180)
			(unlocked yes)
			(layer "F.Fab")
			(hide yes)
			(effects
				(font
					(size 1 1)
					(thickness 0.15)
				)
			)
		)
		(property "Author" "Antmicro"
			(at 0 0 180)
			(unlocked yes)
			(layer "F.Fab")
			(hide yes)
			(effects
				(font
					(size 1 1)
					(thickness 0.15)
				)
			)
		)
		(property "Val" "1u"
			(at 0 0 180)
			(unlocked yes)
			(layer "F.Fab")
			(hide yes)
			(effects
				(font
					(size 1 1)
					(thickness 0.15)
				)
			)
		)
		(property "Voltage" "25V"
			(at 0 0 180)
			(unlocked yes)
			(layer "F.Fab")
			(hide yes)
			(effects
				(font
					(size 1 1)
					(thickness 0.15)
				)
			)
		)
		(property "Dielectric" "X5R"
			(at 0 0 180)
			(unlocked yes)
			(layer "F.Fab")
			(hide yes)
			(effects
				(font
					(size 1 1)
					(thickness 0.15)
				)
			)
		)
		(sheetname "/USB PD/")
		(sheetfile "usb_pd.kicad_sch")
		(attr smd)
		(fp_rect
			(start -0.925 -0.47)
			(end 0.925 0.47)
			(stroke
				(width 0.05)
				(type default)
			)
			(fill no)
			(layer "F.CrtYd")
		)
		(fp_line
			(start 0.504 0.248)
			(end -0.494 0.248)
			(stroke
				(width 0.15)
				(type solid)
			)
			(layer "F.Fab")
		)
		(fp_line
			(start 0.504 -0.25)
			(end 0.504 0.248)
			(stroke
				(width 0.15)
				(type solid)
			)
			(layer "F.Fab")
		)
		(fp_line
			(start -0.494 0.248)
			(end -0.494 -0.25)
			(stroke
				(width 0.15)
				(type solid)
			)
			(layer "F.Fab")
		)
		(fp_line
			(start -0.494 -0.25)
			(end 0.504 -0.25)
			(stroke
				(width 0.15)
				(type solid)
			)
			(layer "F.Fab")
		)
		(pad "1" smd roundrect
			(at -0.48 0 180)
			(size 0.59 0.64)
			(layers "F.Cu" "F.Mask" "F.Paste")
			(roundrect_rratio 0.25)
			(net 2 "GND")
			(pintype "passive")
		)
		(pad "2" smd roundrect
			(at 0.48 0 180)
			(size 0.59 0.64)
			(layers "F.Cu" "F.Mask" "F.Paste")
			(roundrect_rratio 0.25)
			(net 14 "Net-(U1-VREG_2V7)")
			(pintype "passive")
		)
	)
)
